# SCM (Grand Teton) — schematic netlist excerpt (pin names and nets, part order shuffled) for the footprints in the layout excerpt that follows; sources: Cadence DE-HDL packaged netlist, KiCad conversion of 12092022_DA0F0TMDCD0_F0T_Management_Board_D_brd_V3_OCP.brd

R223  Q_RES  33.2 1% CHIP  pkg 0402LF  page 32 : A = JTAG_1_BMC_TMS_R ; B = JTAG_MB_TMS
R626  Q_RES  0 5% CHIP  pkg 0402LF  page 28 : A = FM_SOL_UART_CH_SEL ; B = FM_SOL_UART_CH_SEL_R3

Q4  MOSFET_PCH_GDS  NTR1P02LT1G EMPTY  pkg SOT23_GDS_2-9X1-3XC  page 17
  D  = PGPPA_BMC_AUX_L
  G  = LPC_ESPI_SEL_N
  S  = P3V3_AUX

(kicad_pcb
	(version 20260206)
	(generator "pcbnew")
	(generator_version "10.0")
	(general
		(thickness 1.6)
		(legacy_teardrops no)
	)
	(paper "A4")
	(title_block
		(title "12092022_DA0F0TMDCD0_F0T_Management_Board_D_brd_V3_OCP.brd")
		(comment 1 "Grand Teton / footprints 1404-1406 of 1440")
	)
	(layers
		(0 "F.Cu" signal "TOP")
		(4 "In1.Cu" signal "GND")
		(6 "In2.Cu" signal "IN1")
		(8 "In3.Cu" signal "GND1")
		(10 "In4.Cu" signal "IN2")
		(12 "In5.Cu" signal "VCC")
		(14 "In6.Cu" signal "VCC1")
		(16 "In7.Cu" signal "IN3")
		(18 "In8.Cu" signal "GND2")
		(20 "In9.Cu" signal "IN4")
		(22 "In10.Cu" signal "GND3")
		(2 "B.Cu" signal "BOTTOM")
		(9 "F.Adhes" user "F.Adhesive")
		(11 "B.Adhes" user "B.Adhesive")
		(13 "F.Paste" user "Package Geometry/Pastemask Top")
		(15 "B.Paste" user "Package Geometry/Pastemask Bottom")
		(5 "F.SilkS" user "Ref Des/Silkscreen Top")
		(7 "B.SilkS" user "Ref Des/Silkscreen Bottom")
		(1 "F.Mask" user "Board Geometry/Soldermask Top")
		(3 "B.Mask" user "Board Geometry/Soldermask Bottom")
		(17 "Dwgs.User" user "User.Drawings")
		(19 "Cmts.User" user "User.Comments")
		(21 "Eco1.User" user "User.Eco1")
		(23 "Eco2.User" user "User.Eco2")
		(25 "Edge.Cuts" user "Board Geometry/Outline")
		(27 "Margin" user)
		(31 "F.CrtYd" user "Package Geometry/Place Bound Top")
		(29 "B.CrtYd" user "Package Geometry/Place Bound Bottom")
		(35 "F.Fab" user "Ref Des/Assembly Top")
		(33 "B.Fab" user "Ref Des/Assembly Bottom")
	)
	(footprint ""
		(layer "B.Cu")
		(at 52.555648 -37.005006 90)
		(property "Reference" "R223"
			(at 0 0 90)
			(layer "B.SilkS")
			(hide yes)
			(effects
				(font
					(size 1.27 1.27)
				)
				(justify mirror)
			)
		)
		(property "Value" ""
			(at 0 0 90)
			(layer "B.Fab")
			(effects
				(font
					(size 1.27 1.27)
				)
				(justify mirror)
			)
		)
		(duplicate_pad_numbers_are_jumpers no)
		(fp_line
			(start 0.7874 -0.4064)
			(end -0.7874 -0.4064)
			(stroke
				(width 0.1524)
				(type default)
			)
			(layer "B.SilkS")
		)
		(fp_line
			(start -0.7874 -0.4064)
			(end -0.7874 0.4064)
			(stroke
				(width 0.1524)
				(type default)
			)
			(layer "B.SilkS")
		)
		(fp_line
			(start 0.7874 0.4064)
			(end 0.7874 -0.4064)
			(stroke
				(width 0.1524)
				(type default)
			)
			(layer "B.SilkS")
		)
		(fp_line
			(start -0.7874 0.4064)
			(end 0.7874 0.4064)
			(stroke
				(width 0.1524)
				(type default)
			)
			(layer "B.SilkS")
		)
		(fp_line
			(start 0.67945 -0.305054)
			(end 0.12065 -0.305054)
			(stroke
				(width 0.1)
				(type default)
			)
			(layer "B.Fab")
		)
		(fp_line
			(start 0.12065 -0.305054)
			(end 0.12065 -0.2794)
			(stroke
				(width 0.1)
				(type default)
			)
			(layer "B.Fab")
		)
		(fp_line
			(start -0.12065 -0.3048)
			(end -0.67945 -0.3048)
			(stroke
				(width 0.1)
				(type default)
			)
			(layer "B.Fab")
		)
		(fp_line
			(start -0.67945 -0.3048)
			(end -0.67945 0.3048)
			(stroke
				(width 0.1)
				(type default)
			)
			(layer "B.Fab")
		)
		(fp_line
			(start 0.12065 -0.2794)
			(end -0.12065 -0.2794)
			(stroke
				(width 0.1)
				(type default)
			)
			(layer "B.Fab")
		)
		(fp_line
			(start -0.12065 -0.2794)
			(end -0.12065 -0.3048)
			(stroke
				(width 0.1)
				(type default)
			)
			(layer "B.Fab")
		)
		(fp_line
			(start 0.12065 0.2794)
			(end 0.12065 0.3048)
			(stroke
				(width 0.1)
				(type default)
			)
			(layer "B.Fab")
		)
		(fp_line
			(start -0.120396 0.2794)
			(end 0.12065 0.2794)
			(stroke
				(width 0.1)
				(type default)
			)
			(layer "B.Fab")
		)
		(fp_line
			(start 0.67945 0.3048)
			(end 0.67945 -0.305054)
			(stroke
				(width 0.1)
				(type default)
			)
			(layer "B.Fab")
		)
		(fp_line
			(start 0.12065 0.3048)
			(end 0.67945 0.3048)
			(stroke
				(width 0.1)
				(type default)
			)
			(layer "B.Fab")
		)
		(fp_line
			(start -0.120396 0.3048)
			(end -0.120396 0.2794)
			(stroke
				(width 0.1)
				(type default)
			)
			(layer "B.Fab")
		)
		(fp_line
			(start -0.67945 0.3048)
			(end -0.120396 0.3048)
			(stroke
				(width 0.1)
				(type default)
			)
			(layer "B.Fab")
		)
		(pad "1" smd circle
			(at 0.40005 0 270)
			(size 0 0)
			(layers "B.Cu" "B.Mask" "B.Paste")
			(net "JTAG_1_BMC_TMS_R")
		)
		(pad "2" smd circle
			(at -0.40005 0 270)
			(size 0 0)
			(layers "B.Cu" "B.Mask" "B.Paste")
			(net "JTAG_MB_TMS")
		)
	)
	(footprint ""
		(layer "B.Cu")
		(at 61.18352 -96.06788 180)
		(property "Reference" "R626"
			(at 0 0 0)
			(layer "B.SilkS")
			(hide yes)
			(effects
				(font
					(size 1.27 1.27)
				)
				(justify mirror)
			)
		)
		(property "Value" ""
			(at 0 0 0)
			(layer "B.Fab")
			(effects
				(font
					(size 1.27 1.27)
				)
				(justify mirror)
			)
		)
		(duplicate_pad_numbers_are_jumpers no)
		(fp_line
			(start 0.7874 0.4064)
			(end 0.7874 -0.4064)
			(stroke
				(width 0.1524)
				(type default)
			)
			(layer "B.SilkS")
		)
		(fp_line
			(start 0.7874 -0.4064)
			(end -0.7874 -0.4064)
			(stroke
				(width 0.1524)
				(type default)
			)
			(layer "B.SilkS")
		)
		(fp_line
			(start -0.7874 0.4064)
			(end 0.7874 0.4064)
			(stroke
				(width 0.1524)
				(type default)
			)
			(layer "B.SilkS")
		)
		(fp_line
			(start -0.7874 -0.4064)
			(end -0.7874 0.4064)
			(stroke
				(width 0.1524)
				(type default)
			)
			(layer "B.SilkS")
		)
		(fp_line
			(start 0.67945 0.3048)
			(end 0.67945 -0.305054)
			(stroke
				(width 0.1)
				(type default)
			)
			(layer "B.Fab")
		)
		(fp_line
			(start 0.67945 -0.305054)
			(end 0.12065 -0.305054)
			(stroke
				(width 0.1)
				(type default)
			)
			(layer "B.Fab")
		)
		(fp_line
			(start 0.12065 0.3048)
			(end 0.67945 0.3048)
			(stroke
				(width 0.1)
				(type default)
			)
			(layer "B.Fab")
		)
		(fp_line
			(start 0.12065 0.2794)
			(end 0.12065 0.3048)
			(stroke
				(width 0.1)
				(type default)
			)
			(layer "B.Fab")
		)
		(fp_line
			(start 0.12065 -0.2794)
			(end -0.12065 -0.2794)
			(stroke
				(width 0.1)
				(type default)
			)
			(layer "B.Fab")
		)
		(fp_line
			(start 0.12065 -0.305054)
			(end 0.12065 -0.2794)
			(stroke
				(width 0.1)
				(type default)
			)
			(layer "B.Fab")
		)
		(fp_line
			(start -0.120396 0.3048)
			(end -0.120396 0.2794)
			(stroke
				(width 0.1)
				(type default)
			)
			(layer "B.Fab")
		)
		(fp_line
			(start -0.120396 0.2794)
			(end 0.12065 0.2794)
			(stroke
				(width 0.1)
				(type default)
			)
			(layer "B.Fab")
		)
		(fp_line
			(start -0.12065 -0.2794)
			(end -0.12065 -0.3048)
			(stroke
				(width 0.1)
				(type default)
			)
			(layer "B.Fab")
		)
		(fp_line
			(start -0.12065 -0.3048)
			(end -0.67945 -0.3048)
			(stroke
				(width 0.1)
				(type default)
			)
			(layer "B.Fab")
		)
		(fp_line
			(start -0.67945 0.3048)
			(end -0.120396 0.3048)
			(stroke
				(width 0.1)
				(type default)
			)
			(layer "B.Fab")
		)
		(fp_line
			(start -0.67945 -0.3048)
			(end -0.67945 0.3048)
			(stroke
				(width 0.1)
				(type default)
			)
			(layer "B.Fab")
		)
		(pad "1" smd circle
			(at 0.40005 0)
			(size 0 0)
			(layers "B.Cu" "B.Mask" "B.Paste")
			(net "FM_SOL_UART_CH_SEL")
		)
		(pad "2" smd circle
			(at -0.40005 0)
			(size 0 0)
			(layers "B.Cu" "B.Mask" "B.Paste")
			(net "FM_SOL_UART_CH_SEL_R3")
		)
	)
	(footprint ""
		(layer "B.Cu")
		(at 65.336674 -100.265738)
		(property "Reference" "Q4"
			(at -1.963674 -1.434592 0)
			(unlocked yes)
			(layer "B.SilkS")
			(effects
				(font
					(size 0.7874 0.5842)
					(thickness 0.1524)
				)
				(justify left mirror)
			)
		)
		(property "Value" ""
			(at 0 0 0)
			(layer "B.Fab")
			(effects
				(font
					(size 1.27 1.27)
				)
				(justify mirror)
			)
		)
		(duplicate_pad_numbers_are_jumpers no)
		(fp_line
			(start -1.584198 -1.519936)
			(end -1.584198 1.519936)
			(stroke
				(width 0.1524)
				(type default)
			)
			(layer "B.SilkS")
		)
		(fp_line
			(start -1.584198 1.519936)
			(end 1.584198 1.519936)
			(stroke
				(width 0.1524)
				(type default)
			)
			(layer "B.SilkS")
		)
		(fp_line
			(start 1.584198 -1.519936)
			(end -1.584198 -1.519936)
			(stroke
				(width 0.1524)
				(type default)
			)
			(layer "B.SilkS")
		)
		(fp_line
			(start 1.584198 1.519936)
			(end 1.584198 -1.519936)
			(stroke
				(width 0.1524)
				(type default)
			)
			(layer "B.SilkS")
		)
		(fp_line
			(start -0.700024 -1.519936)
			(end -0.700024 1.519936)
			(stroke
				(width 0.1)
				(type default)
			)
			(layer "B.Fab")
		)
		(fp_line
			(start -0.700024 1.519936)
			(end 0.700024 1.519936)
			(stroke
				(width 0.1)
				(type default)
			)
			(layer "B.Fab")
		)
		(fp_line
			(start 0.700024 -1.519936)
			(end -0.700024 -1.519936)
			(stroke
				(width 0.1)
				(type default)
			)
			(layer "B.Fab")
		)
		(fp_line
			(start 0.700024 1.519936)
			(end 0.700024 -1.519936)
			(stroke
				(width 0.1)
				(type default)
			)
			(layer "B.Fab")
		)
		(pad "D" smd rect
			(at -0.999998 0 270)
			(size 0.8128 0.9144)
			(layers "B.Cu" "B.Mask" "B.Paste")
			(net "PGPPA_BMC_AUX_L")
		)
		(pad "G" smd rect
			(at 0.999998 -0.94996 270)
			(size 0.8128 0.9144)
			(layers "B.Cu" "B.Mask" "B.Paste")
			(net "LPC_ESPI_SEL_N")
		)
		(pad "S" smd rect
			(at 0.999998 0.94996 270)
			(size 0.8128 0.9144)
			(layers "B.Cu" "B.Mask" "B.Paste")
			(net "P3V3_AUX")
		)
	)
)
